# SCM (Grand Teton) — schematic netlist excerpt (pin names and nets, part order shuffled) for the footprints in the layout excerpt that follows; sources: Cadence DE-HDL packaged netlist, KiCad conversion of 12092022_DA0F0TMDCD0_F0T_Management_Board_D_brd_V3_OCP.brd

R151  Q_RES  33.2 1% CHIP  pkg 0402LF  page 12 : A = SGPIO_DO_1 ; B = SGPIO_BMC_M1_DO
D16  SCHOTTKY_12  SBA130Q EMPTY  pkg DFN1610-2_1-6X1  page 23 : A = P5V_AUX ; C = CRT_VCC5_2_D

(kicad_pcb
	(version 20260206)
	(generator "pcbnew")
	(generator_version "10.0")
	(general
		(thickness 1.6)
		(legacy_teardrops no)
	)
	(paper "A4")
	(title_block
		(title "12092022_DA0F0TMDCD0_F0T_Management_Board_D_brd_V3_OCP.brd")
		(comment 1 "Grand Teton / footprints 1076-1077 of 1440")
	)
	(layers
		(0 "F.Cu" signal "TOP")
		(4 "In1.Cu" signal "GND")
		(6 "In2.Cu" signal "IN1")
		(8 "In3.Cu" signal "GND1")
		(10 "In4.Cu" signal "IN2")
		(12 "In5.Cu" signal "VCC")
		(14 "In6.Cu" signal "VCC1")
		(16 "In7.Cu" signal "IN3")
		(18 "In8.Cu" signal "GND2")
		(20 "In9.Cu" signal "IN4")
		(22 "In10.Cu" signal "GND3")
		(2 "B.Cu" signal "BOTTOM")
		(9 "F.Adhes" user "F.Adhesive")
		(11 "B.Adhes" user "B.Adhesive")
		(13 "F.Paste" user "Package Geometry/Pastemask Top")
		(15 "B.Paste" user "Package Geometry/Pastemask Bottom")
		(5 "F.SilkS" user "Ref Des/Silkscreen Top")
		(7 "B.SilkS" user "Ref Des/Silkscreen Bottom")
		(1 "F.Mask" user "Board Geometry/Soldermask Top")
		(3 "B.Mask" user "Board Geometry/Soldermask Bottom")
		(17 "Dwgs.User" user "User.Drawings")
		(19 "Cmts.User" user "User.Comments")
		(21 "Eco1.User" user "User.Eco1")
		(23 "Eco2.User" user "User.Eco2")
		(25 "Edge.Cuts" user "Board Geometry/Outline")
		(27 "Margin" user)
		(31 "F.CrtYd" user "Package Geometry/Place Bound Top")
		(29 "B.CrtYd" user "Package Geometry/Place Bound Bottom")
		(35 "F.Fab" user "Ref Des/Assembly Top")
		(33 "B.Fab" user "Ref Des/Assembly Bottom")
	)
	(footprint ""
		(layer "B.Cu")
		(at 29.591 -20.6502 -90)
		(property "Reference" "D16"
			(at 5.0292 0.02667 270)
			(unlocked yes)
			(layer "B.SilkS")
			(effects
				(font
					(size 0.7874 0.5842)
					(thickness 0.1524)
				)
				(justify left mirror)
			)
		)
		(property "Value" ""
			(at 0 0 90)
			(layer "B.Fab")
			(effects
				(font
					(size 1.27 1.27)
				)
				(justify mirror)
			)
		)
		(duplicate_pad_numbers_are_jumpers no)
		(fp_line
			(start -1.3208 0.635)
			(end 1.056894 0.635)
			(stroke
				(width 0.1524)
				(type default)
			)
			(layer "B.SilkS")
		)
		(fp_line
			(start 1.056894 0.635)
			(end 1.056894 -0.635)
			(stroke
				(width 0.1524)
				(type default)
			)
			(layer "B.SilkS")
		)
		(fp_line
			(start -1.3208 -0.635)
			(end -1.3208 0.635)
			(stroke
				(width 0.1524)
				(type default)
			)
			(layer "B.SilkS")
		)
		(fp_line
			(start -1.3208 -0.635)
			(end -1.3208 0.635)
			(stroke
				(width 0.1524)
				(type default)
			)
			(layer "B.SilkS")
		)
		(fp_line
			(start -1.27 -0.635)
			(end -1.27 0.635)
			(stroke
				(width 0.1524)
				(type default)
			)
			(layer "B.SilkS")
		)
		(fp_line
			(start -1.1684 -0.635)
			(end -1.1684 0.635)
			(stroke
				(width 0.1524)
				(type default)
			)
			(layer "B.SilkS")
		)
		(fp_line
			(start -1.0668 -0.635)
			(end -1.0668 0.635)
			(stroke
				(width 0.1524)
				(type default)
			)
			(layer "B.SilkS")
		)
		(fp_line
			(start 1.056894 -0.635)
			(end -1.3208 -0.635)
			(stroke
				(width 0.1524)
				(type default)
			)
			(layer "B.SilkS")
		)
		(fp_line
			(start -0.824992 0.525018)
			(end -0.824992 -0.525018)
			(stroke
				(width 0.1)
				(type default)
			)
			(layer "B.Fab")
		)
		(fp_line
			(start 0.824992 0.525018)
			(end -0.824992 0.525018)
			(stroke
				(width 0.1)
				(type default)
			)
			(layer "B.Fab")
		)
		(fp_line
			(start -0.824992 -0.525018)
			(end 0.824992 -0.525018)
			(stroke
				(width 0.1)
				(type default)
			)
			(layer "B.Fab")
		)
		(fp_line
			(start 0.824992 -0.525018)
			(end 0.824992 0.525018)
			(stroke
				(width 0.1)
				(type default)
			)
			(layer "B.Fab")
		)
		(fp_text user "+"
			(at 2.3622 -0.22225 270)
			(unlocked yes)
			(layer "B.SilkS")
			(effects
				(font
					(size 1.905 1.4224)
					(thickness 0.1524)
				)
				(justify left mirror)
			)
		)
		(fp_text user "-"
			(at -1.3716 -0.27305 270)
			(unlocked yes)
			(layer "B.SilkS")
			(effects
				(font
					(size 1.905 1.4224)
					(thickness 0.1524)
				)
				(justify left mirror)
			)
		)
		(fp_text user "+"
			(at 2.3622 -0.22225 270)
			(unlocked yes)
			(layer "B.Fab")
			(effects
				(font
					(size 1.905 1.4224)
					(thickness 0.1524)
				)
				(justify left mirror)
			)
		)
		(fp_text user "-"
			(at -1.3716 -0.27305 270)
			(unlocked yes)
			(layer "B.Fab")
			(effects
				(font
					(size 1.905 1.4224)
					(thickness 0.1524)
				)
				(justify left mirror)
			)
		)
		(pad "1" smd rect
			(at 0.612394 0 90)
			(size 0.635 1.016)
			(layers "B.Cu" "B.Mask" "B.Paste")
			(net "P5V_AUX")
		)
		(pad "2" smd rect
			(at -0.612394 0 90)
			(size 0.635 1.016)
			(layers "B.Cu" "B.Mask" "B.Paste")
			(net "CRT_VCC5_2_D")
		)
	)
	(footprint ""
		(layer "B.Cu")
		(at 49.868328 -36.935664 -90)
		(property "Reference" "R151"
			(at 0 0 90)
			(layer "B.SilkS")
			(hide yes)
			(effects
				(font
					(size 1.27 1.27)
				)
				(justify mirror)
			)
		)
		(property "Value" ""
			(at 0 0 90)
			(layer "B.Fab")
			(effects
				(font
					(size 1.27 1.27)
				)
				(justify mirror)
			)
		)
		(duplicate_pad_numbers_are_jumpers no)
		(fp_line
			(start -0.7874 0.4064)
			(end 0.7874 0.4064)
			(stroke
				(width 0.1524)
				(type default)
			)
			(layer "B.SilkS")
		)
		(fp_line
			(start 0.7874 0.4064)
			(end 0.7874 -0.4064)
			(stroke
				(width 0.1524)
				(type default)
			)
			(layer "B.SilkS")
		)
		(fp_line
			(start -0.7874 -0.4064)
			(end -0.7874 0.4064)
			(stroke
				(width 0.1524)
				(type default)
			)
			(layer "B.SilkS")
		)
		(fp_line
			(start 0.7874 -0.4064)
			(end -0.7874 -0.4064)
			(stroke
				(width 0.1524)
				(type default)
			)
			(layer "B.SilkS")
		)
		(fp_line
			(start -0.67945 0.3048)
			(end -0.120396 0.3048)
			(stroke
				(width 0.1)
				(type default)
			)
			(layer "B.Fab")
		)
		(fp_line
			(start -0.120396 0.3048)
			(end -0.120396 0.2794)
			(stroke
				(width 0.1)
				(type default)
			)
			(layer "B.Fab")
		)
		(fp_line
			(start 0.12065 0.3048)
			(end 0.67945 0.3048)
			(stroke
				(width 0.1)
				(type default)
			)
			(layer "B.Fab")
		)
		(fp_line
			(start 0.67945 0.3048)
			(end 0.67945 -0.305054)
			(stroke
				(width 0.1)
				(type default)
			)
			(layer "B.Fab")
		)
		(fp_line
			(start -0.120396 0.2794)
			(end 0.12065 0.2794)
			(stroke
				(width 0.1)
				(type default)
			)
			(layer "B.Fab")
		)
		(fp_line
			(start 0.12065 0.2794)
			(end 0.12065 0.3048)
			(stroke
				(width 0.1)
				(type default)
			)
			(layer "B.Fab")
		)
		(fp_line
			(start -0.12065 -0.2794)
			(end -0.12065 -0.3048)
			(stroke
				(width 0.1)
				(type default)
			)
			(layer "B.Fab")
		)
		(fp_line
			(start 0.12065 -0.2794)
			(end -0.12065 -0.2794)
			(stroke
				(width 0.1)
				(type default)
			)
			(layer "B.Fab")
		)
		(fp_line
			(start -0.67945 -0.3048)
			(end -0.67945 0.3048)
			(stroke
				(width 0.1)
				(type default)
			)
			(layer "B.Fab")
		)
		(fp_line
			(start -0.12065 -0.3048)
			(end -0.67945 -0.3048)
			(stroke
				(width 0.1)
				(type default)
			)
			(layer "B.Fab")
		)
		(fp_line
			(start 0.12065 -0.305054)
			(end 0.12065 -0.2794)
			(stroke
				(width 0.1)
				(type default)
			)
			(layer "B.Fab")
		)
		(fp_line
			(start 0.67945 -0.305054)
			(end 0.12065 -0.305054)
			(stroke
				(width 0.1)
				(type default)
			)
			(layer "B.Fab")
		)
		(pad "1" smd circle
			(at 0.40005 0 90)
			(size 0 0)
			(layers "B.Cu" "B.Mask" "B.Paste")
			(net "SGPIO_DO_1")
		)
		(pad "2" smd circle
			(at -0.40005 0 90)
			(size 0 0)
			(layers "B.Cu" "B.Mask" "B.Paste")
			(net "SGPIO_BMC_M1_DO")
		)
	)
)
